(kicad_pcb
	(version 20260206)
	(generator "pcbnew")
	(generator_version "10.0")
	(general
		(thickness 1.6)
		(legacy_teardrops no)
	)
	(paper "A4")
	(title_block
		(title "12092022_DA0F0TMDCD0_F0T_Management_Board_D_brd_V3_OCP.brd")
		(comment 1 "Grand Teton / footprints 67-73 of 1440")
	)
	(layers
		(0 "F.Cu" signal "TOP")
		(4 "In1.Cu" signal "GND")
		(6 "In2.Cu" signal "IN1")
		(8 "In3.Cu" signal "GND1")
		(10 "In4.Cu" signal "IN2")
		(12 "In5.Cu" signal "VCC")
		(14 "In6.Cu" signal "VCC1")
		(16 "In7.Cu" signal "IN3")
		(18 "In8.Cu" signal "GND2")
		(20 "In9.Cu" signal "IN4")
		(22 "In10.Cu" signal "GND3")
		(2 "B.Cu" signal "BOTTOM")
		(9 "F.Adhes" user "F.Adhesive")
		(11 "B.Adhes" user "B.Adhesive")
		(13 "F.Paste" user "Package Geometry/Pastemask Top")
		(15 "B.Paste" user "Package Geometry/Pastemask Bottom")
		(5 "F.SilkS" user "Ref Des/Silkscreen Top")
		(7 "B.SilkS" user "Ref Des/Silkscreen Bottom")
		(1 "F.Mask" user "Board Geometry/Soldermask Top")
		(3 "B.Mask" user "Board Geometry/Soldermask Bottom")
		(17 "Dwgs.User" user "User.Drawings")
		(19 "Cmts.User" user "User.Comments")
		(21 "Eco1.User" user "User.Eco1")
		(23 "Eco2.User" user "User.Eco2")
		(25 "Edge.Cuts" user "Board Geometry/Outline")
		(27 "Margin" user)
		(31 "F.CrtYd" user "Package Geometry/Place Bound Top")
		(29 "B.CrtYd" user "Package Geometry/Place Bound Bottom")
		(35 "F.Fab" user "Ref Des/Assembly Top")
		(33 "B.Fab" user "Ref Des/Assembly Bottom")
	)
	(footprint ""
		(layer "F.Cu")
		(at 85.35924 -31.877)
		(property "Reference" "C287"
			(at 0 0 0)
			(layer "F.SilkS")
			(hide yes)
			(effects
				(font
					(size 1.27 1.27)
				)
			)
		)
		(property "Value" ""
			(at 0 0 0)
			(layer "F.Fab")
			(effects
				(font
					(size 1.27 1.27)
				)
			)
		)
		(duplicate_pad_numbers_are_jumpers no)
		(fp_line
			(start -0.7874 -0.4064)
			(end 0.7874 -0.4064)
			(stroke
				(width 0.1524)
				(type default)
			)
			(layer "F.SilkS")
		)
		(fp_line
			(start -0.7874 0.4064)
			(end -0.7874 -0.4064)
			(stroke
				(width 0.1524)
				(type default)
			)
			(layer "F.SilkS")
		)
		(fp_line
			(start 0.7874 -0.4064)
			(end 0.7874 0.4064)
			(stroke
				(width 0.1524)
				(type default)
			)
			(layer "F.SilkS")
		)
		(fp_line
			(start 0.7874 0.4064)
			(end -0.7874 0.4064)
			(stroke
				(width 0.1524)
				(type default)
			)
			(layer "F.SilkS")
		)
		(fp_line
			(start -0.67945 -0.305054)
			(end -0.12065 -0.305054)
			(stroke
				(width 0.1)
				(type default)
			)
			(layer "F.Fab")
		)
		(fp_line
			(start -0.67945 0.3048)
			(end -0.67945 -0.305054)
			(stroke
				(width 0.1)
				(type default)
			)
			(layer "F.Fab")
		)
		(fp_line
			(start -0.12065 -0.305054)
			(end -0.12065 -0.2794)
			(stroke
				(width 0.1)
				(type default)
			)
			(layer "F.Fab")
		)
		(fp_line
			(start -0.12065 -0.2794)
			(end 0.12065 -0.2794)
			(stroke
				(width 0.1)
				(type default)
			)
			(layer "F.Fab")
		)
		(fp_line
			(start -0.12065 0.2794)
			(end -0.12065 0.3048)
			(stroke
				(width 0.1)
				(type default)
			)
			(layer "F.Fab")
		)
		(fp_line
			(start -0.12065 0.3048)
			(end -0.67945 0.3048)
			(stroke
				(width 0.1)
				(type default)
			)
			(layer "F.Fab")
		)
		(fp_line
			(start 0.120396 0.2794)
			(end -0.12065 0.2794)
			(stroke
				(width 0.1)
				(type default)
			)
			(layer "F.Fab")
		)
		(fp_line
			(start 0.120396 0.3048)
			(end 0.120396 0.2794)
			(stroke
				(width 0.1)
				(type default)
			)
			(layer "F.Fab")
		)
		(fp_line
			(start 0.12065 -0.3048)
			(end 0.67945 -0.3048)
			(stroke
				(width 0.1)
				(type default)
			)
			(layer "F.Fab")
		)
		(fp_line
			(start 0.12065 -0.2794)
			(end 0.12065 -0.3048)
			(stroke
				(width 0.1)
				(type default)
			)
			(layer "F.Fab")
		)
		(fp_line
			(start 0.67945 -0.3048)
			(end 0.67945 0.3048)
			(stroke
				(width 0.1)
				(type default)
			)
			(layer "F.Fab")
		)
		(fp_line
			(start 0.67945 0.3048)
			(end 0.120396 0.3048)
			(stroke
				(width 0.1)
				(type default)
			)
			(layer "F.Fab")
		)
		(pad "1" smd circle
			(at -0.40005 0)
			(size 0 0)
			(layers "F.Cu" "F.Mask" "F.Paste")
			(net "P5V_AUX")
		)
		(pad "2" smd circle
			(at 0.40005 0)
			(size 0 0)
			(layers "F.Cu" "F.Mask" "F.Paste")
			(net "GND")
		)
	)
	(footprint ""
		(layer "F.Cu")
		(at 34.1884 -108.966 180)
		(property "Reference" "R68"
			(at 0 0 180)
			(layer "F.SilkS")
			(hide yes)
			(effects
				(font
					(size 1.27 1.27)
				)
			)
		)
		(property "Value" ""
			(at 0 0 180)
			(layer "F.Fab")
			(effects
				(font
					(size 1.27 1.27)
				)
			)
		)
		(duplicate_pad_numbers_are_jumpers no)
		(fp_line
			(start 0.7874 0.4064)
			(end -0.7874 0.4064)
			(stroke
				(width 0.1524)
				(type default)
			)
			(layer "F.SilkS")
		)
		(fp_line
			(start 0.7874 -0.4064)
			(end 0.7874 0.4064)
			(stroke
				(width 0.1524)
				(type default)
			)
			(layer "F.SilkS")
		)
		(fp_line
			(start -0.7874 0.4064)
			(end -0.7874 -0.4064)
			(stroke
				(width 0.1524)
				(type default)
			)
			(layer "F.SilkS")
		)
		(fp_line
			(start -0.7874 -0.4064)
			(end 0.7874 -0.4064)
			(stroke
				(width 0.1524)
				(type default)
			)
			(layer "F.SilkS")
		)
		(fp_line
			(start 0.67945 0.3048)
			(end 0.120396 0.3048)
			(stroke
				(width 0.1)
				(type default)
			)
			(layer "F.Fab")
		)
		(fp_line
			(start 0.67945 -0.3048)
			(end 0.67945 0.3048)
			(stroke
				(width 0.1)
				(type default)
			)
			(layer "F.Fab")
		)
		(fp_line
			(start 0.12065 -0.2794)
			(end 0.12065 -0.3048)
			(stroke
				(width 0.1)
				(type default)
			)
			(layer "F.Fab")
		)
		(fp_line
			(start 0.12065 -0.3048)
			(end 0.67945 -0.3048)
			(stroke
				(width 0.1)
				(type default)
			)
			(layer "F.Fab")
		)
		(fp_line
			(start 0.120396 0.3048)
			(end 0.120396 0.2794)
			(stroke
				(width 0.1)
				(type default)
			)
			(layer "F.Fab")
		)
		(fp_line
			(start 0.120396 0.2794)
			(end -0.12065 0.2794)
			(stroke
				(width 0.1)
				(type default)
			)
			(layer "F.Fab")
		)
		(fp_line
			(start -0.12065 0.3048)
			(end -0.67945 0.3048)
			(stroke
				(width 0.1)
				(type default)
			)
			(layer "F.Fab")
		)
		(fp_line
			(start -0.12065 0.2794)
			(end -0.12065 0.3048)
			(stroke
				(width 0.1)
				(type default)
			)
			(layer "F.Fab")
		)
		(fp_line
			(start -0.12065 -0.2794)
			(end 0.12065 -0.2794)
			(stroke
				(width 0.1)
				(type default)
			)
			(layer "F.Fab")
		)
		(fp_line
			(start -0.12065 -0.305054)
			(end -0.12065 -0.2794)
			(stroke
				(width 0.1)
				(type default)
			)
			(layer "F.Fab")
		)
		(fp_line
			(start -0.67945 0.3048)
			(end -0.67945 -0.305054)
			(stroke
				(width 0.1)
				(type default)
			)
			(layer "F.Fab")
		)
		(fp_line
			(start -0.67945 -0.305054)
			(end -0.12065 -0.305054)
			(stroke
				(width 0.1)
				(type default)
			)
			(layer "F.Fab")
		)
		(pad "1" smd circle
			(at -0.40005 0 180)
			(size 0 0)
			(layers "F.Cu" "F.Mask" "F.Paste")
			(net "P3V3_AUX")
		)
		(pad "2" smd circle
			(at 0.40005 0 180)
			(size 0 0)
			(layers "F.Cu" "F.Mask" "F.Paste")
			(net "IRQ_SGPIO_N")
		)
	)
	(footprint ""
		(layer "F.Cu")
		(at -14.404086 -10.924032)
		(property "Reference" "DB5"
			(at -3.5052 -5.552948 0)
			(unlocked yes)
			(layer "F.SilkS")
			(effects
				(font
					(size 0.7874 0.5842)
					(thickness 0.1524)
				)
				(justify left)
			)
		)
		(property "Value" ""
			(at 0 0 0)
			(layer "F.Fab")
			(effects
				(font
					(size 1.27 1.27)
				)
			)
		)
		(duplicate_pad_numbers_are_jumpers no)
		(fp_line
			(start -3.330702 -4.771136)
			(end 3.330702 -4.771136)
			(stroke
				(width 0.1524)
				(type default)
			)
			(layer "F.SilkS")
		)
		(fp_line
			(start 0 4.011168)
			(end -3.330702 -4.771136)
			(stroke
				(width 0.1524)
				(type default)
			)
			(layer "F.SilkS")
		)
		(fp_line
			(start 3.330702 -4.771136)
			(end 0 4.011168)
			(stroke
				(width 0.1524)
				(type default)
			)
			(layer "F.SilkS")
		)
		(fp_line
			(start -3.330702 -4.771136)
			(end 3.330702 -4.771136)
			(stroke
				(width 0.1)
				(type default)
			)
			(layer "F.Fab")
		)
		(fp_line
			(start 0 4.011168)
			(end -3.330702 -4.771136)
			(stroke
				(width 0.1)
				(type default)
			)
			(layer "F.Fab")
		)
		(fp_line
			(start 3.330702 -4.771136)
			(end 0 4.011168)
			(stroke
				(width 0.1)
				(type default)
			)
			(layer "F.Fab")
		)
		(pad "1" thru_hole circle
			(at 0 0)
			(size 2.159 2.159)
			(drill 1.7018)
			(layers "*.Cu" "*.Mask")
			(remove_unused_layers no)
			(net "T_GND")
			(clearance 0.0254)
			(thermal_gap 0.0254)
		)
		(pad "2" thru_hole circle
			(at -1.27 -3.348736)
			(size 2.159 2.159)
			(drill 1.7018)
			(layers "*.Cu" "*.Mask")
			(remove_unused_layers no)
			(net "TDR_SE_50_OHM_IN4")
			(clearance 0.0254)
			(thermal_gap 0.0254)
		)
		(pad "3" thru_hole circle
			(at 1.27 -3.348736)
			(size 2.159 2.159)
			(drill 1.7018)
			(layers "*.Cu" "*.Mask")
			(remove_unused_layers no)
			(net "TDR_SE_50_OHM_IN4")
			(clearance 0.0254)
			(thermal_gap 0.0254)
		)
	)
	(footprint ""
		(layer "F.Cu")
		(at 11.43 -31.837122 -90)
		(property "Reference" "PC217"
			(at 0 0 270)
			(layer "F.SilkS")
			(hide yes)
			(effects
				(font
					(size 1.27 1.27)
				)
			)
		)
		(property "Value" ""
			(at 0 0 270)
			(layer "F.Fab")
			(effects
				(font
					(size 1.27 1.27)
				)
			)
		)
		(duplicate_pad_numbers_are_jumpers no)
		(fp_line
			(start -1.651 0.8382)
			(end -1.651 -0.8382)
			(stroke
				(width 0.1524)
				(type default)
			)
			(layer "F.SilkS")
		)
		(fp_line
			(start 0 0.8382)
			(end 0 -0.8382)
			(stroke
				(width 0.1524)
				(type default)
			)
			(layer "F.SilkS")
		)
		(fp_line
			(start 1.651 0.8382)
			(end -1.651 0.8382)
			(stroke
				(width 0.1524)
				(type default)
			)
			(layer "F.SilkS")
		)
		(fp_line
			(start -1.651 -0.8382)
			(end 1.651 -0.8382)
			(stroke
				(width 0.1524)
				(type default)
			)
			(layer "F.SilkS")
		)
		(fp_line
			(start 1.651 -0.8382)
			(end 1.651 0.8382)
			(stroke
				(width 0.1524)
				(type default)
			)
			(layer "F.SilkS")
		)
		(fp_line
			(start -1.55956 0.7366)
			(end -1.524 0.7366)
			(stroke
				(width 0.1)
				(type default)
			)
			(layer "F.Fab")
		)
		(fp_line
			(start -1.524 0.7366)
			(end 1.524 0.7366)
			(stroke
				(width 0.1)
				(type default)
			)
			(layer "F.Fab")
		)
		(fp_line
			(start 1.524 0.7366)
			(end 1.55956 0.7366)
			(stroke
				(width 0.1)
				(type default)
			)
			(layer "F.Fab")
		)
		(fp_line
			(start 1.55956 0.7366)
			(end 1.55956 -0.7366)
			(stroke
				(width 0.1)
				(type default)
			)
			(layer "F.Fab")
		)
		(fp_line
			(start -1.55956 -0.7366)
			(end -1.55956 0.7366)
			(stroke
				(width 0.1)
				(type default)
			)
			(layer "F.Fab")
		)
		(fp_line
			(start -1.524 -0.7366)
			(end -1.55956 -0.7366)
			(stroke
				(width 0.1)
				(type default)
			)
			(layer "F.Fab")
		)
		(fp_line
			(start 1.524 -0.7366)
			(end -1.524 -0.7366)
			(stroke
				(width 0.1)
				(type default)
			)
			(layer "F.Fab")
		)
		(fp_line
			(start 1.55956 -0.7366)
			(end 1.524 -0.7366)
			(stroke
				(width 0.1)
				(type default)
			)
			(layer "F.Fab")
		)
		(pad "1" smd rect
			(at -0.94996 0 90)
			(size 1.1176 1.3716)
			(layers "F.Cu" "F.Mask" "F.Paste")
			(net "P5V_AUX")
		)
		(pad "2" smd rect
			(at 0.94996 0 90)
			(size 1.1176 1.3716)
			(layers "F.Cu" "F.Mask" "F.Paste")
			(net "GND")
		)
	)
	(footprint ""
		(layer "F.Cu")
		(at 46.863 -24.384)
		(property "Reference" "R383"
			(at 0 0 0)
			(layer "F.SilkS")
			(hide yes)
			(effects
				(font
					(size 1.27 1.27)
				)
			)
		)
		(property "Value" ""
			(at 0 0 0)
			(layer "F.Fab")
			(effects
				(font
					(size 1.27 1.27)
				)
			)
		)
		(duplicate_pad_numbers_are_jumpers no)
		(fp_line
			(start -0.7874 -0.4064)
			(end 0.7874 -0.4064)
			(stroke
				(width 0.1524)
				(type default)
			)
			(layer "F.SilkS")
		)
		(fp_line
			(start -0.7874 0.4064)
			(end -0.7874 -0.4064)
			(stroke
				(width 0.1524)
				(type default)
			)
			(layer "F.SilkS")
		)
		(fp_line
			(start 0.7874 -0.4064)
			(end 0.7874 0.4064)
			(stroke
				(width 0.1524)
				(type default)
			)
			(layer "F.SilkS")
		)
		(fp_line
			(start 0.7874 0.4064)
			(end -0.7874 0.4064)
			(stroke
				(width 0.1524)
				(type default)
			)
			(layer "F.SilkS")
		)
		(fp_line
			(start -0.67945 -0.305054)
			(end -0.12065 -0.305054)
			(stroke
				(width 0.1)
				(type default)
			)
			(layer "F.Fab")
		)
		(fp_line
			(start -0.67945 0.3048)
			(end -0.67945 -0.305054)
			(stroke
				(width 0.1)
				(type default)
			)
			(layer "F.Fab")
		)
		(fp_line
			(start -0.12065 -0.305054)
			(end -0.12065 -0.2794)
			(stroke
				(width 0.1)
				(type default)
			)
			(layer "F.Fab")
		)
		(fp_line
			(start -0.12065 -0.2794)
			(end 0.12065 -0.2794)
			(stroke
				(width 0.1)
				(type default)
			)
			(layer "F.Fab")
		)
		(fp_line
			(start -0.12065 0.2794)
			(end -0.12065 0.3048)
			(stroke
				(width 0.1)
				(type default)
			)
			(layer "F.Fab")
		)
		(fp_line
			(start -0.12065 0.3048)
			(end -0.67945 0.3048)
			(stroke
				(width 0.1)
				(type default)
			)
			(layer "F.Fab")
		)
		(fp_line
			(start 0.120396 0.2794)
			(end -0.12065 0.2794)
			(stroke
				(width 0.1)
				(type default)
			)
			(layer "F.Fab")
		)
		(fp_line
			(start 0.120396 0.3048)
			(end 0.120396 0.2794)
			(stroke
				(width 0.1)
				(type default)
			)
			(layer "F.Fab")
		)
		(fp_line
			(start 0.12065 -0.3048)
			(end 0.67945 -0.3048)
			(stroke
				(width 0.1)
				(type default)
			)
			(layer "F.Fab")
		)
		(fp_line
			(start 0.12065 -0.2794)
			(end 0.12065 -0.3048)
			(stroke
				(width 0.1)
				(type default)
			)
			(layer "F.Fab")
		)
		(fp_line
			(start 0.67945 -0.3048)
			(end 0.67945 0.3048)
			(stroke
				(width 0.1)
				(type default)
			)
			(layer "F.Fab")
		)
		(fp_line
			(start 0.67945 0.3048)
			(end 0.120396 0.3048)
			(stroke
				(width 0.1)
				(type default)
			)
			(layer "F.Fab")
		)
		(pad "1" smd circle
			(at -0.40005 0)
			(size 0 0)
			(layers "F.Cu" "F.Mask" "F.Paste")
			(net "P3V3_AUX")
		)
		(pad "2" smd circle
			(at 0.40005 0)
			(size 0 0)
			(layers "F.Cu" "F.Mask" "F.Paste")
			(net "USB_OC0_REAR_N")
		)
	)
	(footprint ""
		(layer "F.Cu")
		(at 53.537612 -28.027376 -90)
		(property "Reference" "C37"
			(at 0 0 270)
			(layer "F.SilkS")
			(hide yes)
			(effects
				(font
					(size 1.27 1.27)
				)
			)
		)
		(property "Value" ""
			(at 0 0 270)
			(layer "F.Fab")
			(effects
				(font
					(size 1.27 1.27)
				)
			)
		)
		(duplicate_pad_numbers_are_jumpers no)
		(fp_line
			(start -0.7874 0.4064)
			(end -0.7874 -0.4064)
			(stroke
				(width 0.1524)
				(type default)
			)
			(layer "F.SilkS")
		)
		(fp_line
			(start 0.7874 0.4064)
			(end -0.7874 0.4064)
			(stroke
				(width 0.1524)
				(type default)
			)
			(layer "F.SilkS")
		)
		(fp_line
			(start -0.7874 -0.4064)
			(end 0.7874 -0.4064)
			(stroke
				(width 0.1524)
				(type default)
			)
			(layer "F.SilkS")
		)
		(fp_line
			(start 0.7874 -0.4064)
			(end 0.7874 0.4064)
			(stroke
				(width 0.1524)
				(type default)
			)
			(layer "F.SilkS")
		)
		(fp_line
			(start -0.67945 0.3048)
			(end -0.67945 -0.305054)
			(stroke
				(width 0.1)
				(type default)
			)
			(layer "F.Fab")
		)
		(fp_line
			(start -0.12065 0.3048)
			(end -0.67945 0.3048)
			(stroke
				(width 0.1)
				(type default)
			)
			(layer "F.Fab")
		)
		(fp_line
			(start 0.120396 0.3048)
			(end 0.120396 0.2794)
			(stroke
				(width 0.1)
				(type default)
			)
			(layer "F.Fab")
		)
		(fp_line
			(start 0.67945 0.3048)
			(end 0.120396 0.3048)
			(stroke
				(width 0.1)
				(type default)
			)
			(layer "F.Fab")
		)
		(fp_line
			(start -0.12065 0.2794)
			(end -0.12065 0.3048)
			(stroke
				(width 0.1)
				(type default)
			)
			(layer "F.Fab")
		)
		(fp_line
			(start 0.120396 0.2794)
			(end -0.12065 0.2794)
			(stroke
				(width 0.1)
				(type default)
			)
			(layer "F.Fab")
		)
		(fp_line
			(start -0.12065 -0.2794)
			(end 0.12065 -0.2794)
			(stroke
				(width 0.1)
				(type default)
			)
			(layer "F.Fab")
		)
		(fp_line
			(start 0.12065 -0.2794)
			(end 0.12065 -0.3048)
			(stroke
				(width 0.1)
				(type default)
			)
			(layer "F.Fab")
		)
		(fp_line
			(start 0.12065 -0.3048)
			(end 0.67945 -0.3048)
			(stroke
				(width 0.1)
				(type default)
			)
			(layer "F.Fab")
		)
		(fp_line
			(start 0.67945 -0.3048)
			(end 0.67945 0.3048)
			(stroke
				(width 0.1)
				(type default)
			)
			(layer "F.Fab")
		)
		(fp_line
			(start -0.67945 -0.305054)
			(end -0.12065 -0.305054)
			(stroke
				(width 0.1)
				(type default)
			)
			(layer "F.Fab")
		)
		(fp_line
			(start -0.12065 -0.305054)
			(end -0.12065 -0.2794)
			(stroke
				(width 0.1)
				(type default)
			)
			(layer "F.Fab")
		)
		(pad "1" smd circle
			(at -0.40005 0 270)
			(size 0 0)
			(layers "F.Cu" "F.Mask" "F.Paste")
			(net "P3V3_RGM")
		)
		(pad "2" smd circle
			(at 0.40005 0 270)
			(size 0 0)
			(layers "F.Cu" "F.Mask" "F.Paste")
			(net "GND")
		)
	)
	(footprint ""
		(layer "F.Cu")
		(at 32.512 -13.7922)
		(property "Reference" "C276"
			(at 0 0 0)
			(layer "F.SilkS")
			(hide yes)
			(effects
				(font
					(size 1.27 1.27)
				)
			)
		)
		(property "Value" ""
			(at 0 0 0)
			(layer "F.Fab")
			(effects
				(font
					(size 1.27 1.27)
				)
			)
		)
		(duplicate_pad_numbers_are_jumpers no)
		(fp_line
			(start -0.7874 -0.4064)
			(end 0.7874 -0.4064)
			(stroke
				(width 0.1524)
				(type default)
			)
			(layer "F.SilkS")
		)
		(fp_line
			(start -0.7874 0.4064)
			(end -0.7874 -0.4064)
			(stroke
				(width 0.1524)
				(type default)
			)
			(layer "F.SilkS")
		)
		(fp_line
			(start 0.7874 -0.4064)
			(end 0.7874 0.4064)
			(stroke
				(width 0.1524)
				(type default)
			)
			(layer "F.SilkS")
		)
		(fp_line
			(start 0.7874 0.4064)
			(end -0.7874 0.4064)
			(stroke
				(width 0.1524)
				(type default)
			)
			(layer "F.SilkS")
		)
		(fp_line
			(start -0.67945 -0.305054)
			(end -0.12065 -0.305054)
			(stroke
				(width 0.1)
				(type default)
			)
			(layer "F.Fab")
		)
		(fp_line
			(start -0.67945 0.3048)
			(end -0.67945 -0.305054)
			(stroke
				(width 0.1)
				(type default)
			)
			(layer "F.Fab")
		)
		(fp_line
			(start -0.12065 -0.305054)
			(end -0.12065 -0.2794)
			(stroke
				(width 0.1)
				(type default)
			)
			(layer "F.Fab")
		)
		(fp_line
			(start -0.12065 -0.2794)
			(end 0.12065 -0.2794)
			(stroke
				(width 0.1)
				(type default)
			)
			(layer "F.Fab")
		)
		(fp_line
			(start -0.12065 0.2794)
			(end -0.12065 0.3048)
			(stroke
				(width 0.1)
				(type default)
			)
			(layer "F.Fab")
		)
		(fp_line
			(start -0.12065 0.3048)
			(end -0.67945 0.3048)
			(stroke
				(width 0.1)
				(type default)
			)
			(layer "F.Fab")
		)
		(fp_line
			(start 0.120396 0.2794)
			(end -0.12065 0.2794)
			(stroke
				(width 0.1)
				(type default)
			)
			(layer "F.Fab")
		)
		(fp_line
			(start 0.120396 0.3048)
			(end 0.120396 0.2794)
			(stroke
				(width 0.1)
				(type default)
			)
			(layer "F.Fab")
		)
		(fp_line
			(start 0.12065 -0.3048)
			(end 0.67945 -0.3048)
			(stroke
				(width 0.1)
				(type default)
			)
			(layer "F.Fab")
		)
		(fp_line
			(start 0.12065 -0.2794)
			(end 0.12065 -0.3048)
			(stroke
				(width 0.1)
				(type default)
			)
			(layer "F.Fab")
		)
		(fp_line
			(start 0.67945 -0.3048)
			(end 0.67945 0.3048)
			(stroke
				(width 0.1)
				(type default)
			)
			(layer "F.Fab")
		)
		(fp_line
			(start 0.67945 0.3048)
			(end 0.120396 0.3048)
			(stroke
				(width 0.1)
				(type default)
			)
			(layer "F.Fab")
		)
		(pad "1" smd circle
			(at -0.40005 0)
			(size 0 0)
			(layers "F.Cu" "F.Mask" "F.Paste")
			(net "P3V3_AUX")
		)
		(pad "2" smd circle
			(at 0.40005 0)
			(size 0 0)
			(layers "F.Cu" "F.Mask" "F.Paste")
			(net "GND")
		)
	)
)
